FILE_TYPE = MACRO_DRAWING;
SET COLOR_WIRE YELLOW;
SET COLOR_PROP MONO;
SET COLOR_DOT WHITE;
SET COLOR_ARC YELLOW;
SET COLOR_BODY GREEN;
SET COLOR_NOTE MONO;
SET PROP_DISPLAY VALUE;
SET PAGE_NUMBER P258;
FORCEADD INTEL_CORP_BPAGE..1
(-1475 1900);
FORCEPROP 1 LAST CDS_CON_LAST_MODIFIED Fri Jun 16 17:49:38 2017
J 0
(-2900 2225);
PAINT ORANGE (-2900 2225);
DISPLAY INVISIBLE (-2900 2225);
FORCEPROP 2 LAST CUSTOM_TXT_CDS <XR_PAGE_TITLE>
J 0
(-9365 7150);
DISPLAY 0.638298 (-9365 7150);
PAINT PINK (-9365 7150);
DISPLAY INVISIBLE (-9365 7150);
FORCEPROP 2 LAST CUSTOM_TXT_CDS <CURRENT_DESIGN_SHEET> OF <TOTAL_DESIGN_SHEETS>
J 0
(-2000 1925);
PAINT ORANGE (-2000 1925);
FORCEPROP 2 LAST CUSTOM_TXT_CDS <CON_LAST_MODIFIED>
J 0
(-5475 2000);
PAINT ORANGE (-5475 2000);
FORCEPROP 1 LAST SCH_TITLE SYMBOL DEFINITIONS
J 0
(-9425 1950);
DISPLAY 2.468085 (-9425 1950);
PAINT ORANGE (-9425 1950);
FORCEPROP 2 LAST CDS_LIB mstr_symbols
J 0
(-1475 1900);
PAINT MONO (-1475 1900);
DISPLAY INVISIBLE (-1475 1900);
FORCEPROP 2 LAST PAGE_BORDER TRUE
J 0
(-9365 7150);
DISPLAY 0.638298 (-9365 7150);
PAINT PINK (-9365 7150);
DISPLAY INVISIBLE (-9365 7150);
FORCEPROP 1 LAST COMMENT_BODY TRUE
J 0
(-1463 1912);
DISPLAY 0.468085 (-1463 1912);
PAINT GREEN (-1463 1912);
DISPLAY INVISIBLE (-1463 1912);
FORCEPROP 2 LAST CDS_XR_PAGE_TITLE CR-264 : @BASEBOARD_FAB2_LIB.BASEBOARD_FAB2(SCH_1):PAGE264
J 0
(-9365 7150);
DISPLAY 0.638298 (-9365 7150);
PAINT PINK (-9365 7150);
DISPLAY INVISIBLE (-9365 7150);
FORCENOTE
$CDS_IMAGE|Wistron symbol definition.jpg|6465|2736
(-5475 4500) 0;
DISPLAY LEFT (-5475 4500);
QUIT
